(kicad_pcb
	(version 20260206)
	(generator "pcbnew")
	(generator_version "10.0")
	(general
		(thickness 1.6)
		(legacy_teardrops no)
	)
	(paper "A4")
	(title_block
		(title "01162023_DA0F0TEBIF0_F0T_Expander_BD_F_brd_V02_OCP.brd")
		(comment 1 "Grand Teton / footprints 1015-1021 of 9728")
	)
	(layers
		(0 "F.Cu" signal "TOP")
		(4 "In1.Cu" signal "GND")
		(6 "In2.Cu" signal "VCC")
		(8 "In3.Cu" signal "VCC1")
		(10 "In4.Cu" signal "GND1")
		(12 "In5.Cu" signal "IN1")
		(14 "In6.Cu" signal "GND2")
		(16 "In7.Cu" signal "IN2")
		(18 "In8.Cu" signal "GND3")
		(20 "In9.Cu" signal "IN3")
		(22 "In10.Cu" signal "GND4")
		(24 "In11.Cu" signal "IN4")
		(26 "In12.Cu" signal "GND5")
		(28 "In13.Cu" signal "IN5")
		(30 "In14.Cu" signal "GND6")
		(32 "In15.Cu" signal "IN6")
		(34 "In16.Cu" signal "GND7")
		(2 "B.Cu" signal "BOTTOM")
		(9 "F.Adhes" user "F.Adhesive")
		(11 "B.Adhes" user "B.Adhesive")
		(13 "F.Paste" user "Package Geometry/Pastemask Top")
		(15 "B.Paste" user "Package Geometry/Pastemask Bottom")
		(5 "F.SilkS" user "Ref Des/Silkscreen Top")
		(7 "B.SilkS" user "Ref Des/Silkscreen Bottom")
		(1 "F.Mask" user "Board Geometry/Soldermask Top")
		(3 "B.Mask" user "Board Geometry/Soldermask Bottom")
		(17 "Dwgs.User" user "User.Drawings")
		(19 "Cmts.User" user "User.Comments")
		(21 "Eco1.User" user "User.Eco1")
		(23 "Eco2.User" user "User.Eco2")
		(25 "Edge.Cuts" user "Board Geometry/Outline")
		(27 "Margin" user)
		(31 "F.CrtYd" user "Package Geometry/Place Bound Top")
		(29 "B.CrtYd" user "Package Geometry/Place Bound Bottom")
		(35 "F.Fab" user "Ref Des/Assembly Top")
		(33 "B.Fab" user "Ref Des/Assembly Bottom")
	)
	(footprint ""
		(layer "F.Cu")
		(at 98.514408 -66.32194 90)
		(property "Reference" "R5845"
			(at 0 0 90)
			(layer "F.SilkS")
			(hide yes)
			(effects
				(font
					(size 1.27 1.27)
				)
			)
		)
		(property "Value" ""
			(at 0 0 90)
			(layer "F.Fab")
			(effects
				(font
					(size 1.27 1.27)
				)
			)
		)
		(duplicate_pad_numbers_are_jumpers no)
		(fp_line
			(start 0.7874 -0.4064)
			(end 0.7874 0.4064)
			(stroke
				(width 0.1524)
				(type default)
			)
			(layer "F.SilkS")
		)
		(fp_line
			(start -0.7874 -0.4064)
			(end 0.7874 -0.4064)
			(stroke
				(width 0.1524)
				(type default)
			)
			(layer "F.SilkS")
		)
		(fp_line
			(start 0.7874 0.4064)
			(end -0.7874 0.4064)
			(stroke
				(width 0.1524)
				(type default)
			)
			(layer "F.SilkS")
		)
		(fp_line
			(start -0.7874 0.4064)
			(end -0.7874 -0.4064)
			(stroke
				(width 0.1524)
				(type default)
			)
			(layer "F.SilkS")
		)
		(fp_line
			(start -0.12065 -0.305054)
			(end -0.12065 -0.2794)
			(stroke
				(width 0.1)
				(type default)
			)
			(layer "F.Fab")
		)
		(fp_line
			(start -0.67945 -0.305054)
			(end -0.12065 -0.305054)
			(stroke
				(width 0.1)
				(type default)
			)
			(layer "F.Fab")
		)
		(fp_line
			(start 0.67945 -0.3048)
			(end 0.67945 0.3048)
			(stroke
				(width 0.1)
				(type default)
			)
			(layer "F.Fab")
		)
		(fp_line
			(start 0.12065 -0.3048)
			(end 0.67945 -0.3048)
			(stroke
				(width 0.1)
				(type default)
			)
			(layer "F.Fab")
		)
		(fp_line
			(start 0.12065 -0.2794)
			(end 0.12065 -0.3048)
			(stroke
				(width 0.1)
				(type default)
			)
			(layer "F.Fab")
		)
		(fp_line
			(start -0.12065 -0.2794)
			(end 0.12065 -0.2794)
			(stroke
				(width 0.1)
				(type default)
			)
			(layer "F.Fab")
		)
		(fp_line
			(start 0.120396 0.2794)
			(end -0.12065 0.2794)
			(stroke
				(width 0.1)
				(type default)
			)
			(layer "F.Fab")
		)
		(fp_line
			(start -0.12065 0.2794)
			(end -0.12065 0.3048)
			(stroke
				(width 0.1)
				(type default)
			)
			(layer "F.Fab")
		)
		(fp_line
			(start 0.67945 0.3048)
			(end 0.120396 0.3048)
			(stroke
				(width 0.1)
				(type default)
			)
			(layer "F.Fab")
		)
		(fp_line
			(start 0.120396 0.3048)
			(end 0.120396 0.2794)
			(stroke
				(width 0.1)
				(type default)
			)
			(layer "F.Fab")
		)
		(fp_line
			(start -0.12065 0.3048)
			(end -0.67945 0.3048)
			(stroke
				(width 0.1)
				(type default)
			)
			(layer "F.Fab")
		)
		(fp_line
			(start -0.67945 0.3048)
			(end -0.67945 -0.305054)
			(stroke
				(width 0.1)
				(type default)
			)
			(layer "F.Fab")
		)
		(pad "1" smd circle
			(at -0.40005 0 90)
			(size 0 0)
			(layers "F.Cu" "F.Mask" "F.Paste")
			(net "SSD3_PWR_EN_R")
		)
		(pad "2" smd circle
			(at 0.40005 0 90)
			(size 0 0)
			(layers "F.Cu" "F.Mask" "F.Paste")
			(net "P12V_SSD3_CO_EN")
		)
	)
	(footprint ""
		(layer "F.Cu")
		(at 172.401992 -350.098614 90)
		(property "Reference" "C393"
			(at 0 0 90)
			(layer "F.SilkS")
			(hide yes)
			(effects
				(font
					(size 1.27 1.27)
				)
			)
		)
		(property "Value" ""
			(at 0 0 90)
			(layer "F.Fab")
			(effects
				(font
					(size 1.27 1.27)
				)
			)
		)
		(duplicate_pad_numbers_are_jumpers no)
		(fp_line
			(start 0.299974 -0.150114)
			(end 0.299974 0.150114)
			(stroke
				(width 0.1)
				(type default)
			)
			(layer "F.Fab")
		)
		(fp_line
			(start -0.299974 -0.150114)
			(end 0.299974 -0.150114)
			(stroke
				(width 0.1)
				(type default)
			)
			(layer "F.Fab")
		)
		(fp_line
			(start 0.299974 0.150114)
			(end -0.299974 0.150114)
			(stroke
				(width 0.1)
				(type default)
			)
			(layer "F.Fab")
		)
		(fp_line
			(start -0.299974 0.150114)
			(end -0.299974 -0.150114)
			(stroke
				(width 0.1)
				(type default)
			)
			(layer "F.Fab")
		)
		(pad "1" smd rect
			(at -0.2667 0 90)
			(size 0.3048 0.381)
			(layers "F.Cu" "F.Mask" "F.Paste")
			(net "P5E_PEX1_STN7_TX_DN<117>")
		)
		(pad "2" smd rect
			(at 0.2667 0 90)
			(size 0.3048 0.381)
			(layers "F.Cu" "F.Mask" "F.Paste")
			(net "P5E_PEX1_STN7_TX_C_DN<117>")
		)
	)
	(footprint ""
		(layer "F.Cu")
		(at 394.574014 -72.766682 90)
		(property "Reference" "PR7089"
			(at 0 0 90)
			(layer "F.SilkS")
			(hide yes)
			(effects
				(font
					(size 1.27 1.27)
				)
			)
		)
		(property "Value" ""
			(at 0 0 90)
			(layer "F.Fab")
			(effects
				(font
					(size 1.27 1.27)
				)
			)
		)
		(duplicate_pad_numbers_are_jumpers no)
		(fp_line
			(start 0.7874 -0.4064)
			(end 0.7874 0.4064)
			(stroke
				(width 0.1524)
				(type default)
			)
			(layer "F.SilkS")
		)
		(fp_line
			(start -0.7874 -0.4064)
			(end 0.7874 -0.4064)
			(stroke
				(width 0.1524)
				(type default)
			)
			(layer "F.SilkS")
		)
		(fp_line
			(start 0.7874 0.4064)
			(end -0.7874 0.4064)
			(stroke
				(width 0.1524)
				(type default)
			)
			(layer "F.SilkS")
		)
		(fp_line
			(start -0.7874 0.4064)
			(end -0.7874 -0.4064)
			(stroke
				(width 0.1524)
				(type default)
			)
			(layer "F.SilkS")
		)
		(fp_line
			(start -0.12065 -0.305054)
			(end -0.12065 -0.2794)
			(stroke
				(width 0.1)
				(type default)
			)
			(layer "F.Fab")
		)
		(fp_line
			(start -0.67945 -0.305054)
			(end -0.12065 -0.305054)
			(stroke
				(width 0.1)
				(type default)
			)
			(layer "F.Fab")
		)
		(fp_line
			(start 0.67945 -0.3048)
			(end 0.67945 0.3048)
			(stroke
				(width 0.1)
				(type default)
			)
			(layer "F.Fab")
		)
		(fp_line
			(start 0.12065 -0.3048)
			(end 0.67945 -0.3048)
			(stroke
				(width 0.1)
				(type default)
			)
			(layer "F.Fab")
		)
		(fp_line
			(start 0.12065 -0.2794)
			(end 0.12065 -0.3048)
			(stroke
				(width 0.1)
				(type default)
			)
			(layer "F.Fab")
		)
		(fp_line
			(start -0.12065 -0.2794)
			(end 0.12065 -0.2794)
			(stroke
				(width 0.1)
				(type default)
			)
			(layer "F.Fab")
		)
		(fp_line
			(start 0.120396 0.2794)
			(end -0.12065 0.2794)
			(stroke
				(width 0.1)
				(type default)
			)
			(layer "F.Fab")
		)
		(fp_line
			(start -0.12065 0.2794)
			(end -0.12065 0.3048)
			(stroke
				(width 0.1)
				(type default)
			)
			(layer "F.Fab")
		)
		(fp_line
			(start 0.67945 0.3048)
			(end 0.120396 0.3048)
			(stroke
				(width 0.1)
				(type default)
			)
			(layer "F.Fab")
		)
		(fp_line
			(start 0.120396 0.3048)
			(end 0.120396 0.2794)
			(stroke
				(width 0.1)
				(type default)
			)
			(layer "F.Fab")
		)
		(fp_line
			(start -0.12065 0.3048)
			(end -0.67945 0.3048)
			(stroke
				(width 0.1)
				(type default)
			)
			(layer "F.Fab")
		)
		(fp_line
			(start -0.67945 0.3048)
			(end -0.67945 -0.305054)
			(stroke
				(width 0.1)
				(type default)
			)
			(layer "F.Fab")
		)
		(pad "1" smd circle
			(at -0.40005 0 90)
			(size 0 0)
			(layers "F.Cu" "F.Mask" "F.Paste")
			(net "P12V_SSD13_CO_MODE")
		)
		(pad "2" smd circle
			(at 0.40005 0 90)
			(size 0 0)
			(layers "F.Cu" "F.Mask" "F.Paste")
			(net "GND")
		)
	)
	(footprint ""
		(layer "F.Cu")
		(at 176.063402 -177.456592 90)
		(property "Reference" "C4498"
			(at 0 0 90)
			(layer "F.SilkS")
			(hide yes)
			(effects
				(font
					(size 1.27 1.27)
				)
			)
		)
		(property "Value" ""
			(at 0 0 90)
			(layer "F.Fab")
			(effects
				(font
					(size 1.27 1.27)
				)
			)
		)
		(duplicate_pad_numbers_are_jumpers no)
		(fp_line
			(start 0.7874 -0.4064)
			(end 0.7874 0.4064)
			(stroke
				(width 0.1524)
				(type default)
			)
			(layer "F.SilkS")
		)
		(fp_line
			(start -0.7874 -0.4064)
			(end 0.7874 -0.4064)
			(stroke
				(width 0.1524)
				(type default)
			)
			(layer "F.SilkS")
		)
		(fp_line
			(start 0.7874 0.4064)
			(end -0.7874 0.4064)
			(stroke
				(width 0.1524)
				(type default)
			)
			(layer "F.SilkS")
		)
		(fp_line
			(start -0.7874 0.4064)
			(end -0.7874 -0.4064)
			(stroke
				(width 0.1524)
				(type default)
			)
			(layer "F.SilkS")
		)
		(fp_line
			(start -0.12065 -0.305054)
			(end -0.12065 -0.2794)
			(stroke
				(width 0.1)
				(type default)
			)
			(layer "F.Fab")
		)
		(fp_line
			(start -0.67945 -0.305054)
			(end -0.12065 -0.305054)
			(stroke
				(width 0.1)
				(type default)
			)
			(layer "F.Fab")
		)
		(fp_line
			(start 0.67945 -0.3048)
			(end 0.67945 0.3048)
			(stroke
				(width 0.1)
				(type default)
			)
			(layer "F.Fab")
		)
		(fp_line
			(start 0.12065 -0.3048)
			(end 0.67945 -0.3048)
			(stroke
				(width 0.1)
				(type default)
			)
			(layer "F.Fab")
		)
		(fp_line
			(start 0.12065 -0.2794)
			(end 0.12065 -0.3048)
			(stroke
				(width 0.1)
				(type default)
			)
			(layer "F.Fab")
		)
		(fp_line
			(start -0.12065 -0.2794)
			(end 0.12065 -0.2794)
			(stroke
				(width 0.1)
				(type default)
			)
			(layer "F.Fab")
		)
		(fp_line
			(start 0.120396 0.2794)
			(end -0.12065 0.2794)
			(stroke
				(width 0.1)
				(type default)
			)
			(layer "F.Fab")
		)
		(fp_line
			(start -0.12065 0.2794)
			(end -0.12065 0.3048)
			(stroke
				(width 0.1)
				(type default)
			)
			(layer "F.Fab")
		)
		(fp_line
			(start 0.67945 0.3048)
			(end 0.120396 0.3048)
			(stroke
				(width 0.1)
				(type default)
			)
			(layer "F.Fab")
		)
		(fp_line
			(start 0.120396 0.3048)
			(end 0.120396 0.2794)
			(stroke
				(width 0.1)
				(type default)
			)
			(layer "F.Fab")
		)
		(fp_line
			(start -0.12065 0.3048)
			(end -0.67945 0.3048)
			(stroke
				(width 0.1)
				(type default)
			)
			(layer "F.Fab")
		)
		(fp_line
			(start -0.67945 0.3048)
			(end -0.67945 -0.305054)
			(stroke
				(width 0.1)
				(type default)
			)
			(layer "F.Fab")
		)
		(pad "1" smd circle
			(at -0.40005 0 90)
			(size 0 0)
			(layers "F.Cu" "F.Mask" "F.Paste")
			(net "NIC3_CLK_EN_R_N")
		)
		(pad "2" smd circle
			(at 0.40005 0 90)
			(size 0 0)
			(layers "F.Cu" "F.Mask" "F.Paste")
			(net "GND")
		)
	)
	(footprint ""
		(layer "F.Cu")
		(at 341.372444 -356.244906 90)
		(property "Reference" "C522"
			(at 0 0 90)
			(layer "F.SilkS")
			(hide yes)
			(effects
				(font
					(size 1.27 1.27)
				)
			)
		)
		(property "Value" ""
			(at 0 0 90)
			(layer "F.Fab")
			(effects
				(font
					(size 1.27 1.27)
				)
			)
		)
		(duplicate_pad_numbers_are_jumpers no)
		(fp_line
			(start 0.299974 -0.150114)
			(end 0.299974 0.150114)
			(stroke
				(width 0.1)
				(type default)
			)
			(layer "F.Fab")
		)
		(fp_line
			(start -0.299974 -0.150114)
			(end 0.299974 -0.150114)
			(stroke
				(width 0.1)
				(type default)
			)
			(layer "F.Fab")
		)
		(fp_line
			(start 0.299974 0.150114)
			(end -0.299974 0.150114)
			(stroke
				(width 0.1)
				(type default)
			)
			(layer "F.Fab")
		)
		(fp_line
			(start -0.299974 0.150114)
			(end -0.299974 -0.150114)
			(stroke
				(width 0.1)
				(type default)
			)
			(layer "F.Fab")
		)
		(pad "1" smd rect
			(at -0.2667 0 90)
			(size 0.3048 0.381)
			(layers "F.Cu" "F.Mask" "F.Paste")
			(net "P5E_PEX2_STN5_TX_DN<94>")
		)
		(pad "2" smd rect
			(at 0.2667 0 90)
			(size 0.3048 0.381)
			(layers "F.Cu" "F.Mask" "F.Paste")
			(net "P5E_PEX2_STN5_TX_C_DN<94>")
		)
	)
	(footprint ""
		(layer "F.Cu")
		(at 336.55 -205.232 -90)
		(property "Reference" "R4122"
			(at 0 0 270)
			(layer "F.SilkS")
			(hide yes)
			(effects
				(font
					(size 1.27 1.27)
				)
			)
		)
		(property "Value" ""
			(at 0 0 270)
			(layer "F.Fab")
			(effects
				(font
					(size 1.27 1.27)
				)
			)
		)
		(duplicate_pad_numbers_are_jumpers no)
		(fp_line
			(start -0.7874 0.4064)
			(end -0.7874 -0.4064)
			(stroke
				(width 0.1524)
				(type default)
			)
			(layer "F.SilkS")
		)
		(fp_line
			(start 0.7874 0.4064)
			(end -0.7874 0.4064)
			(stroke
				(width 0.1524)
				(type default)
			)
			(layer "F.SilkS")
		)
		(fp_line
			(start -0.7874 -0.4064)
			(end 0.7874 -0.4064)
			(stroke
				(width 0.1524)
				(type default)
			)
			(layer "F.SilkS")
		)
		(fp_line
			(start 0.7874 -0.4064)
			(end 0.7874 0.4064)
			(stroke
				(width 0.1524)
				(type default)
			)
			(layer "F.SilkS")
		)
		(fp_line
			(start -0.67945 0.3048)
			(end -0.67945 -0.305054)
			(stroke
				(width 0.1)
				(type default)
			)
			(layer "F.Fab")
		)
		(fp_line
			(start -0.12065 0.3048)
			(end -0.67945 0.3048)
			(stroke
				(width 0.1)
				(type default)
			)
			(layer "F.Fab")
		)
		(fp_line
			(start 0.120396 0.3048)
			(end 0.120396 0.2794)
			(stroke
				(width 0.1)
				(type default)
			)
			(layer "F.Fab")
		)
		(fp_line
			(start 0.67945 0.3048)
			(end 0.120396 0.3048)
			(stroke
				(width 0.1)
				(type default)
			)
			(layer "F.Fab")
		)
		(fp_line
			(start -0.12065 0.2794)
			(end -0.12065 0.3048)
			(stroke
				(width 0.1)
				(type default)
			)
			(layer "F.Fab")
		)
		(fp_line
			(start 0.120396 0.2794)
			(end -0.12065 0.2794)
			(stroke
				(width 0.1)
				(type default)
			)
			(layer "F.Fab")
		)
		(fp_line
			(start -0.12065 -0.2794)
			(end 0.12065 -0.2794)
			(stroke
				(width 0.1)
				(type default)
			)
			(layer "F.Fab")
		)
		(fp_line
			(start 0.12065 -0.2794)
			(end 0.12065 -0.3048)
			(stroke
				(width 0.1)
				(type default)
			)
			(layer "F.Fab")
		)
		(fp_line
			(start 0.12065 -0.3048)
			(end 0.67945 -0.3048)
			(stroke
				(width 0.1)
				(type default)
			)
			(layer "F.Fab")
		)
		(fp_line
			(start 0.67945 -0.3048)
			(end 0.67945 0.3048)
			(stroke
				(width 0.1)
				(type default)
			)
			(layer "F.Fab")
		)
		(fp_line
			(start -0.67945 -0.305054)
			(end -0.12065 -0.305054)
			(stroke
				(width 0.1)
				(type default)
			)
			(layer "F.Fab")
		)
		(fp_line
			(start -0.12065 -0.305054)
			(end -0.12065 -0.2794)
			(stroke
				(width 0.1)
				(type default)
			)
			(layer "F.Fab")
		)
		(pad "1" smd circle
			(at -0.40005 0 270)
			(size 0 0)
			(layers "F.Cu" "F.Mask" "F.Paste")
			(net "SSD9_CLK_EN_N")
		)
		(pad "2" smd circle
			(at 0.40005 0 270)
			(size 0 0)
			(layers "F.Cu" "F.Mask" "F.Paste")
			(net "SSD9_CLK_EN_R_N")
		)
	)
	(footprint ""
		(layer "F.Cu")
		(at 456.149202 -247.791224 180)
		(property "Reference" "U433"
			(at 1.255014 -4.651248 0)
			(unlocked yes)
			(layer "F.SilkS")
			(effects
				(font
					(size 0.7874 0.5842)
					(thickness 0.1524)
				)
				(justify left)
			)
		)
		(property "Value" ""
			(at 0 0 180)
			(layer "F.Fab")
			(effects
				(font
					(size 1.27 1.27)
				)
			)
		)
		(duplicate_pad_numbers_are_jumpers no)
		(fp_line
			(start 1.525016 1.525016)
			(end 1.525016 1.3208)
			(stroke
				(width 0.1524)
				(type default)
			)
			(layer "F.SilkS")
		)
		(fp_line
			(start 1.525016 1.525016)
			(end -1.525016 1.525016)
			(stroke
				(width 0.1524)
				(type default)
			)
			(layer "F.SilkS")
		)
		(fp_line
			(start 1.525016 -1.3208)
			(end 1.525016 -1.525016)
			(stroke
				(width 0.1524)
				(type default)
			)
			(layer "F.SilkS")
		)
		(fp_line
			(start 1.525016 -1.525016)
			(end 0.9398 -1.525016)
			(stroke
				(width 0.1524)
				(type default)
			)
			(layer "F.SilkS")
		)
		(fp_line
			(start 1.525016 -1.525016)
			(end -1.525016 -1.525016)
			(stroke
				(width 0.1524)
				(type default)
			)
			(layer "F.SilkS")
		)
		(fp_line
			(start 0.9906 1.525016)
			(end 1.525016 1.525016)
			(stroke
				(width 0.1524)
				(type default)
			)
			(layer "F.SilkS")
		)
		(fp_line
			(start -0.8636 -1.525016)
			(end -1.525016 -1.525016)
			(stroke
				(width 0.1524)
				(type default)
			)
			(layer "F.SilkS")
		)
		(fp_line
			(start -1.525016 1.525016)
			(end -0.889 1.525016)
			(stroke
				(width 0.1524)
				(type default)
			)
			(layer "F.SilkS")
		)
		(fp_line
			(start -1.525016 1.3208)
			(end -1.525016 1.525016)
			(stroke
				(width 0.1524)
				(type default)
			)
			(layer "F.SilkS")
		)
		(fp_line
			(start -1.525016 -1.525016)
			(end -1.525016 -1.3208)
			(stroke
				(width 0.1524)
				(type default)
			)
			(layer "F.SilkS")
		)
		(fp_poly
			(pts
				(xy -2.260854 -0.979424) (xy -1.96088 -1.8796) (xy -2.560828 -1.8796)
			)
			(stroke
				(width 0)
				(type default)
			)
			(fill yes)
			(layer "F.SilkS")
		)
		(fp_line
			(start 1.525016 1.525016)
			(end -1.525016 1.525016)
			(stroke
				(width 0.1)
				(type default)
			)
			(layer "F.Fab")
		)
		(fp_line
			(start 1.525016 -1.525016)
			(end 1.525016 1.525016)
			(stroke
				(width 0.1)
				(type default)
			)
			(layer "F.Fab")
		)
		(fp_line
			(start -1.525016 1.525016)
			(end -1.525016 -1.525016)
			(stroke
				(width 0.1)
				(type default)
			)
			(layer "F.Fab")
		)
		(fp_line
			(start -1.525016 -1.525016)
			(end 1.525016 -1.525016)
			(stroke
				(width 0.1)
				(type default)
			)
			(layer "F.Fab")
		)
		(fp_poly
			(pts
				(xy -2.0701 -0.999998) (xy -2.977896 -1.302512) (xy -2.977896 -0.697484)
			)
			(stroke
				(width 0)
				(type default)
			)
			(fill yes)
			(layer "F.Fab")
		)
		(pad "1" smd rect
			(at -1.550162 -0.999998 90)
			(size 0.2794 0.9144)
			(layers "F.Cu" "F.Mask" "F.Paste")
			(net "P1V8_PLL0_PEX3")
		)
		(pad "2" smd rect
			(at -1.550162 -0.500126 90)
			(size 0.2794 0.9144)
			(layers "F.Cu" "F.Mask" "F.Paste")
			(net "P1V8_PLL0_PEX3")
		)
		(pad "3" smd rect
			(at -1.550162 0 90)
			(size 0.2794 0.9144)
			(layers "F.Cu" "F.Mask" "F.Paste")
			(net "P1V8_PLL0_PEX3")
		)
		(pad "4" smd rect
			(at -1.550162 0.500126 90)
			(size 0.2794 0.9144)
			(layers "F.Cu" "F.Mask" "F.Paste")
			(net "P1V8_PLL_PEX3_ADJ")
		)
		(pad "5" smd rect
			(at -1.550162 0.999998 270)
			(size 0.2794 0.9144)
			(layers "F.Cu" "F.Mask" "F.Paste")
			(net "PWRGD_PEX3_P1V8_PLL")
		)
		(pad "6" smd rect
			(at 1.550162 0.999998 270)
			(size 0.2794 0.9144)
			(layers "F.Cu" "F.Mask" "F.Paste")
			(net "PEX3_P1V8_PLL_EN")
		)
		(pad "7" smd rect
			(at 1.550162 0.500126 90)
			(size 0.2794 0.9144)
			(layers "F.Cu" "F.Mask" "F.Paste")
			(net "P3V3_AUX")
		)
		(pad "8" smd rect
			(at 1.550162 0 90)
			(size 0.2794 0.9144)
			(layers "F.Cu" "F.Mask" "F.Paste")
			(net "P3V3_AUX")
		)
		(pad "9" smd rect
			(at 1.550162 -0.500126 90)
			(size 0.2794 0.9144)
			(layers "F.Cu" "F.Mask" "F.Paste")
			(net "P3V3_AUX")
		)
		(pad "10" smd rect
			(at 1.550162 -0.999998 90)
			(size 0.2794 0.9144)
			(layers "F.Cu" "F.Mask" "F.Paste")
			(net "P5V_AUX")
		)
		(pad "TH" smd rect
			(at 0 0 180)
			(size 1.7526 2.667)
			(layers "F.Cu" "F.Mask" "F.Paste")
			(net "GND")
		)
	)
)
